(kicad_pcb
	(version 20260206)
	(generator "pcbnew")
	(generator_version "10.0")
	(general
		(thickness 1.6)
		(legacy_teardrops no)
	)
	(paper "A4")
	(title_block
		(title "03242023_DA0F0TMBIJ0_F0T_Motherboard_J_brd_V01_OCP.brd")
		(comment 1 "Grand Teton / footprints 912-916 of 6105")
	)
	(layers
		(0 "F.Cu" signal "TOP")
		(4 "In1.Cu" signal "GND")
		(6 "In2.Cu" signal "IN1")
		(8 "In3.Cu" signal "GND1")
		(10 "In4.Cu" signal "IN2")
		(12 "In5.Cu" signal "GND2")
		(14 "In6.Cu" signal "IN3")
		(16 "In7.Cu" signal "GND3")
		(18 "In8.Cu" signal "VCC")
		(20 "In9.Cu" signal "VCC1")
		(22 "In10.Cu" signal "GND4")
		(24 "In11.Cu" signal "IN4")
		(26 "In12.Cu" signal "GND5")
		(28 "In13.Cu" signal "IN5")
		(30 "In14.Cu" signal "GND6")
		(32 "In15.Cu" signal "IN6")
		(34 "In16.Cu" signal "GND7")
		(2 "B.Cu" signal "BOTTOM")
		(9 "F.Adhes" user "F.Adhesive")
		(11 "B.Adhes" user "B.Adhesive")
		(13 "F.Paste" user "Package Geometry/Pastemask Top")
		(15 "B.Paste" user "Package Geometry/Pastemask Bottom")
		(5 "F.SilkS" user "Ref Des/Silkscreen Top")
		(7 "B.SilkS" user "Ref Des/Silkscreen Bottom")
		(1 "F.Mask" user "Board Geometry/Soldermask Top")
		(3 "B.Mask" user "Board Geometry/Soldermask Bottom")
		(17 "Dwgs.User" user "User.Drawings")
		(19 "Cmts.User" user "User.Comments")
		(21 "Eco1.User" user "User.Eco1")
		(23 "Eco2.User" user "User.Eco2")
		(25 "Edge.Cuts" user "Board Geometry/Outline")
		(27 "Margin" user)
		(31 "F.CrtYd" user "Package Geometry/Place Bound Top")
		(29 "B.CrtYd" user "Package Geometry/Place Bound Bottom")
		(35 "F.Fab" user "Ref Des/Assembly Top")
		(33 "B.Fab" user "Ref Des/Assembly Bottom")
	)
	(footprint ""
		(layer "F.Cu")
		(at 451.497192 -20.979638)
		(property "Reference" "PU203"
			(at 1.984248 -5.8674 0)
			(unlocked yes)
			(layer "F.SilkS")
			(effects
				(font
					(size 0.7874 0.5842)
					(thickness 0.1524)
				)
				(justify left)
			)
		)
		(property "Value" ""
			(at 0 0 0)
			(layer "F.Fab")
			(effects
				(font
					(size 1.27 1.27)
				)
			)
		)
		(duplicate_pad_numbers_are_jumpers no)
		(fp_line
			(start -1.774952 -1.039876)
			(end -1.774952 1.039876)
			(stroke
				(width 0.1524)
				(type default)
			)
			(layer "F.SilkS")
		)
		(fp_line
			(start -1.774952 1.039876)
			(end 1.774952 1.039876)
			(stroke
				(width 0.1524)
				(type default)
			)
			(layer "F.SilkS")
		)
		(fp_line
			(start 1.774952 -1.039876)
			(end -1.774952 -1.039876)
			(stroke
				(width 0.1524)
				(type default)
			)
			(layer "F.SilkS")
		)
		(fp_line
			(start 1.774952 1.039876)
			(end 1.774952 -1.039876)
			(stroke
				(width 0.1524)
				(type default)
			)
			(layer "F.SilkS")
		)
		(fp_poly
			(pts
				(xy -1.769872 -1.039876) (xy -1.769872 -0.249936) (xy -2.531872 -0.249936) (xy -2.531872 -1.801876)
				(xy -0.999998 -1.801876) (xy -0.999998 -1.039876)
			)
			(stroke
				(width 0)
				(type default)
			)
			(fill yes)
			(layer "F.SilkS")
		)
		(fp_line
			(start -1.769872 -1.039876)
			(end -1.769872 1.039876)
			(stroke
				(width 0.1)
				(type default)
			)
			(layer "F.Fab")
		)
		(fp_line
			(start -1.769872 1.039876)
			(end 1.769872 1.039876)
			(stroke
				(width 0.1)
				(type default)
			)
			(layer "F.Fab")
		)
		(fp_line
			(start 1.769872 -1.039876)
			(end -1.769872 -1.039876)
			(stroke
				(width 0.1)
				(type default)
			)
			(layer "F.Fab")
		)
		(fp_line
			(start 1.769872 1.039876)
			(end 1.769872 -1.039876)
			(stroke
				(width 0.1)
				(type default)
			)
			(layer "F.Fab")
		)
		(fp_poly
			(pts
				(xy -1.769872 -1.039876) (xy -0.999998 -1.039876) (xy -0.999998 -1.801876) (xy -2.531872 -1.801876)
				(xy -2.531872 -0.249936) (xy -1.769872 -0.249936)
			)
			(stroke
				(width 0)
				(type default)
			)
			(fill yes)
			(layer "F.Fab")
		)
		(pad "A1" smd circle
			(at -1.500124 -0.750062)
			(size 0.2286 0.2286)
			(layers "F.Cu" "F.Mask" "F.Paste")
			(net "P12V_OCP_SENSE_1")
		)
		(pad "A2" smd circle
			(at -0.999998 -0.750062)
			(size 0.2286 0.2286)
			(layers "F.Cu" "F.Mask" "F.Paste")
			(net "P12V_OCP_VCC_1")
		)
		(pad "A3" smd circle
			(at -0.499872 -0.750062)
			(size 0.2286 0.2286)
			(layers "F.Cu" "F.Mask" "F.Paste")
			(net "P12V_AUX")
		)
		(pad "A4" smd circle
			(at 0 -0.750062)
			(size 0.2286 0.2286)
			(layers "F.Cu" "F.Mask" "F.Paste")
			(net "P12V_OCP_SFF")
		)
		(pad "A5" smd circle
			(at 0.499872 -0.750062)
			(size 0.2286 0.2286)
			(layers "F.Cu" "F.Mask" "F.Paste")
			(net "P12V_AUX")
		)
		(pad "A6" smd circle
			(at 0.999998 -0.750062)
			(size 0.2286 0.2286)
			(layers "F.Cu" "F.Mask" "F.Paste")
			(net "P12V_OCP_GATE_1")
		)
		(pad "A7" smd circle
			(at 1.500124 -0.750062)
			(size 0.2286 0.2286)
			(layers "F.Cu" "F.Mask" "F.Paste")
			(net "GND")
		)
		(pad "B1" smd circle
			(at -1.500124 -0.249936)
			(size 0.2286 0.2286)
			(layers "F.Cu" "F.Mask" "F.Paste")
			(net "P12V_OCP_CB_1")
		)
		(pad "B2" smd circle
			(at -0.999998 -0.249936)
			(size 0.2286 0.2286)
			(layers "F.Cu" "F.Mask" "F.Paste")
			(net "GND")
		)
		(pad "B3" smd circle
			(at -0.499872 -0.249936)
			(size 0.2286 0.2286)
			(layers "F.Cu" "F.Mask" "F.Paste")
			(net "P12V_AUX")
		)
		(pad "B4" smd circle
			(at 0 -0.249936)
			(size 0.2286 0.2286)
			(layers "F.Cu" "F.Mask" "F.Paste")
			(net "P12V_OCP_SFF")
		)
		(pad "B5" smd circle
			(at 0.499872 -0.249936)
			(size 0.2286 0.2286)
			(layers "F.Cu" "F.Mask" "F.Paste")
			(net "P12V_AUX")
		)
		(pad "B6" smd circle
			(at 0.999998 -0.249936)
			(size 0.2286 0.2286)
			(layers "F.Cu" "F.Mask" "F.Paste")
			(net "P12V_OCP_SFF")
		)
		(pad "B7" smd circle
			(at 1.500124 -0.249936)
			(size 0.2286 0.2286)
			(layers "F.Cu" "F.Mask" "F.Paste")
			(net "GND")
		)
		(pad "C1" smd circle
			(at -1.500124 0.249936)
			(size 0.2286 0.2286)
			(layers "F.Cu" "F.Mask" "F.Paste")
			(net "GND")
		)
		(pad "C2" smd circle
			(at -0.999998 0.249936)
			(size 0.2286 0.2286)
			(layers "F.Cu" "F.Mask" "F.Paste")
			(net "GND")
		)
		(pad "C3" smd circle
			(at -0.499872 0.249936)
			(size 0.2286 0.2286)
			(layers "F.Cu" "F.Mask" "F.Paste")
			(net "P12V_AUX")
		)
		(pad "C4" smd circle
			(at 0 0.249936)
			(size 0.2286 0.2286)
			(layers "F.Cu" "F.Mask" "F.Paste")
			(net "P12V_OCP_SFF")
		)
		(pad "C5" smd circle
			(at 0.499872 0.249936)
			(size 0.2286 0.2286)
			(layers "F.Cu" "F.Mask" "F.Paste")
			(net "P12V_AUX")
		)
		(pad "C6" smd circle
			(at 0.999998 0.249936)
			(size 0.2286 0.2286)
			(layers "F.Cu" "F.Mask" "F.Paste")
			(net "P12V_OCP_SFF")
		)
		(pad "C7" smd circle
			(at 1.500124 0.249936)
			(size 0.2286 0.2286)
			(layers "F.Cu" "F.Mask" "F.Paste")
			(net "P12V_OCP_FAULT_1")
		)
		(pad "D1" smd circle
			(at -1.500124 0.750062)
			(size 0.2286 0.2286)
			(layers "F.Cu" "F.Mask" "F.Paste")
			(net "P12V_OCP_REG_1")
		)
		(pad "D2" smd circle
			(at -0.999998 0.750062)
			(size 0.2286 0.2286)
			(layers "F.Cu" "F.Mask" "F.Paste")
			(net "P12V_OCP_UV_1")
		)
		(pad "D3" smd circle
			(at -0.499872 0.750062)
			(size 0.2286 0.2286)
			(layers "F.Cu" "F.Mask" "F.Paste")
			(net "P12V_OCP_OV_1")
		)
		(pad "D4" smd circle
			(at 0 0.750062)
			(size 0.2286 0.2286)
			(layers "F.Cu" "F.Mask" "F.Paste")
			(net "P12V_OCP_SFF")
		)
		(pad "D5" smd circle
			(at 0.499872 0.750062)
			(size 0.2286 0.2286)
			(layers "F.Cu" "F.Mask" "F.Paste")
			(net "P12V_AUX")
		)
		(pad "D6" smd circle
			(at 0.999998 0.750062)
			(size 0.2286 0.2286)
			(layers "F.Cu" "F.Mask" "F.Paste")
			(net "P12V_OCP_SFF")
		)
		(pad "D7" smd circle
			(at 1.500124 0.750062)
			(size 0.2286 0.2286)
			(layers "F.Cu" "F.Mask" "F.Paste")
			(net "P12V_OCP_PWRGD_1")
		)
	)
	(footprint ""
		(layer "F.Cu")
		(at 224.21215 -47.612046)
		(property "Reference" "R2287"
			(at 0 0 0)
			(layer "F.SilkS")
			(hide yes)
			(effects
				(font
					(size 1.27 1.27)
				)
			)
		)
		(property "Value" ""
			(at 0 0 0)
			(layer "F.Fab")
			(effects
				(font
					(size 1.27 1.27)
				)
			)
		)
		(duplicate_pad_numbers_are_jumpers no)
		(fp_line
			(start -0.7874 -0.4064)
			(end 0.7874 -0.4064)
			(stroke
				(width 0.1524)
				(type default)
			)
			(layer "F.SilkS")
		)
		(fp_line
			(start -0.7874 0.4064)
			(end -0.7874 -0.4064)
			(stroke
				(width 0.1524)
				(type default)
			)
			(layer "F.SilkS")
		)
		(fp_line
			(start 0.7874 -0.4064)
			(end 0.7874 0.4064)
			(stroke
				(width 0.1524)
				(type default)
			)
			(layer "F.SilkS")
		)
		(fp_line
			(start 0.7874 0.4064)
			(end -0.7874 0.4064)
			(stroke
				(width 0.1524)
				(type default)
			)
			(layer "F.SilkS")
		)
		(fp_line
			(start -0.67945 -0.305054)
			(end -0.12065 -0.305054)
			(stroke
				(width 0.1)
				(type default)
			)
			(layer "F.Fab")
		)
		(fp_line
			(start -0.67945 0.3048)
			(end -0.67945 -0.305054)
			(stroke
				(width 0.1)
				(type default)
			)
			(layer "F.Fab")
		)
		(fp_line
			(start -0.12065 -0.305054)
			(end -0.12065 -0.2794)
			(stroke
				(width 0.1)
				(type default)
			)
			(layer "F.Fab")
		)
		(fp_line
			(start -0.12065 -0.2794)
			(end 0.12065 -0.2794)
			(stroke
				(width 0.1)
				(type default)
			)
			(layer "F.Fab")
		)
		(fp_line
			(start -0.12065 0.2794)
			(end -0.12065 0.3048)
			(stroke
				(width 0.1)
				(type default)
			)
			(layer "F.Fab")
		)
		(fp_line
			(start -0.12065 0.3048)
			(end -0.67945 0.3048)
			(stroke
				(width 0.1)
				(type default)
			)
			(layer "F.Fab")
		)
		(fp_line
			(start 0.120396 0.2794)
			(end -0.12065 0.2794)
			(stroke
				(width 0.1)
				(type default)
			)
			(layer "F.Fab")
		)
		(fp_line
			(start 0.120396 0.3048)
			(end 0.120396 0.2794)
			(stroke
				(width 0.1)
				(type default)
			)
			(layer "F.Fab")
		)
		(fp_line
			(start 0.12065 -0.3048)
			(end 0.67945 -0.3048)
			(stroke
				(width 0.1)
				(type default)
			)
			(layer "F.Fab")
		)
		(fp_line
			(start 0.12065 -0.2794)
			(end 0.12065 -0.3048)
			(stroke
				(width 0.1)
				(type default)
			)
			(layer "F.Fab")
		)
		(fp_line
			(start 0.67945 -0.3048)
			(end 0.67945 0.3048)
			(stroke
				(width 0.1)
				(type default)
			)
			(layer "F.Fab")
		)
		(fp_line
			(start 0.67945 0.3048)
			(end 0.120396 0.3048)
			(stroke
				(width 0.1)
				(type default)
			)
			(layer "F.Fab")
		)
		(pad "1" smd circle
			(at -0.40005 0)
			(size 0 0)
			(layers "F.Cu" "F.Mask" "F.Paste")
			(net "P3V3_E1S_0")
		)
		(pad "2" smd circle
			(at 0.40005 0)
			(size 0 0)
			(layers "F.Cu" "F.Mask" "F.Paste")
			(net "E1S_0_PERST1_CLKREQ_N")
		)
	)
	(footprint ""
		(layer "F.Cu")
		(at 440.0804 -20.440396 180)
		(property "Reference" "PC2082"
			(at 0 0 180)
			(layer "F.SilkS")
			(hide yes)
			(effects
				(font
					(size 1.27 1.27)
				)
			)
		)
		(property "Value" ""
			(at 0 0 180)
			(layer "F.Fab")
			(effects
				(font
					(size 1.27 1.27)
				)
			)
		)
		(duplicate_pad_numbers_are_jumpers no)
		(fp_line
			(start 1.524 0.762)
			(end -1.524 0.762)
			(stroke
				(width 0.1524)
				(type default)
			)
			(layer "F.SilkS")
		)
		(fp_line
			(start 1.524 -0.762)
			(end 1.524 0.762)
			(stroke
				(width 0.1524)
				(type default)
			)
			(layer "F.SilkS")
		)
		(fp_line
			(start -1.524 0.762)
			(end -1.524 -0.762)
			(stroke
				(width 0.1524)
				(type default)
			)
			(layer "F.SilkS")
		)
		(fp_line
			(start -1.524 -0.762)
			(end 1.524 -0.762)
			(stroke
				(width 0.1524)
				(type default)
			)
			(layer "F.SilkS")
		)
		(fp_line
			(start 1.1049 0.724916)
			(end 1.1049 -0.724916)
			(stroke
				(width 0.1)
				(type default)
			)
			(layer "F.Fab")
		)
		(fp_line
			(start 1.1049 -0.724916)
			(end -1.1049 -0.724916)
			(stroke
				(width 0.1)
				(type default)
			)
			(layer "F.Fab")
		)
		(fp_line
			(start -1.1049 0.724916)
			(end 1.1049 0.724916)
			(stroke
				(width 0.1)
				(type default)
			)
			(layer "F.Fab")
		)
		(fp_line
			(start -1.1049 -0.724916)
			(end -1.1049 0.724916)
			(stroke
				(width 0.1)
				(type default)
			)
			(layer "F.Fab")
		)
		(pad "1" smd rect
			(at -0.889 0)
			(size 1.016 1.27)
			(layers "F.Cu" "F.Mask" "F.Paste")
			(net "P12V_OCP_SFF")
		)
		(pad "2" smd rect
			(at 0.889 0)
			(size 1.016 1.27)
			(layers "F.Cu" "F.Mask" "F.Paste")
			(net "GND")
		)
	)
	(footprint ""
		(layer "F.Cu")
		(at 153.21788 -41.811448)
		(property "Reference" "R3297"
			(at 0 0 0)
			(layer "F.SilkS")
			(hide yes)
			(effects
				(font
					(size 1.27 1.27)
				)
			)
		)
		(property "Value" ""
			(at 0 0 0)
			(layer "F.Fab")
			(effects
				(font
					(size 1.27 1.27)
				)
			)
		)
		(duplicate_pad_numbers_are_jumpers no)
		(fp_line
			(start -0.7874 -0.4064)
			(end 0.7874 -0.4064)
			(stroke
				(width 0.1524)
				(type default)
			)
			(layer "F.SilkS")
		)
		(fp_line
			(start -0.7874 0.4064)
			(end -0.7874 -0.4064)
			(stroke
				(width 0.1524)
				(type default)
			)
			(layer "F.SilkS")
		)
		(fp_line
			(start 0.7874 -0.4064)
			(end 0.7874 0.4064)
			(stroke
				(width 0.1524)
				(type default)
			)
			(layer "F.SilkS")
		)
		(fp_line
			(start 0.7874 0.4064)
			(end -0.7874 0.4064)
			(stroke
				(width 0.1524)
				(type default)
			)
			(layer "F.SilkS")
		)
		(fp_line
			(start -0.67945 -0.305054)
			(end -0.12065 -0.305054)
			(stroke
				(width 0.1)
				(type default)
			)
			(layer "F.Fab")
		)
		(fp_line
			(start -0.67945 0.3048)
			(end -0.67945 -0.305054)
			(stroke
				(width 0.1)
				(type default)
			)
			(layer "F.Fab")
		)
		(fp_line
			(start -0.12065 -0.305054)
			(end -0.12065 -0.2794)
			(stroke
				(width 0.1)
				(type default)
			)
			(layer "F.Fab")
		)
		(fp_line
			(start -0.12065 -0.2794)
			(end 0.12065 -0.2794)
			(stroke
				(width 0.1)
				(type default)
			)
			(layer "F.Fab")
		)
		(fp_line
			(start -0.12065 0.2794)
			(end -0.12065 0.3048)
			(stroke
				(width 0.1)
				(type default)
			)
			(layer "F.Fab")
		)
		(fp_line
			(start -0.12065 0.3048)
			(end -0.67945 0.3048)
			(stroke
				(width 0.1)
				(type default)
			)
			(layer "F.Fab")
		)
		(fp_line
			(start 0.120396 0.2794)
			(end -0.12065 0.2794)
			(stroke
				(width 0.1)
				(type default)
			)
			(layer "F.Fab")
		)
		(fp_line
			(start 0.120396 0.3048)
			(end 0.120396 0.2794)
			(stroke
				(width 0.1)
				(type default)
			)
			(layer "F.Fab")
		)
		(fp_line
			(start 0.12065 -0.3048)
			(end 0.67945 -0.3048)
			(stroke
				(width 0.1)
				(type default)
			)
			(layer "F.Fab")
		)
		(fp_line
			(start 0.12065 -0.2794)
			(end 0.12065 -0.3048)
			(stroke
				(width 0.1)
				(type default)
			)
			(layer "F.Fab")
		)
		(fp_line
			(start 0.67945 -0.3048)
			(end 0.67945 0.3048)
			(stroke
				(width 0.1)
				(type default)
			)
			(layer "F.Fab")
		)
		(fp_line
			(start 0.67945 0.3048)
			(end 0.120396 0.3048)
			(stroke
				(width 0.1)
				(type default)
			)
			(layer "F.Fab")
		)
		(pad "1" smd circle
			(at -0.40005 0)
			(size 0 0)
			(layers "F.Cu" "F.Mask" "F.Paste")
			(net "LED_HDD_ACTIVITY_B_N")
		)
		(pad "2" smd circle
			(at 0.40005 0)
			(size 0 0)
			(layers "F.Cu" "F.Mask" "F.Paste")
			(net "GND")
		)
	)
	(footprint ""
		(layer "F.Cu")
		(at 39.827454 -108.047282 180)
		(property "Reference" "R3684"
			(at 0 0 180)
			(layer "F.SilkS")
			(hide yes)
			(effects
				(font
					(size 1.27 1.27)
				)
			)
		)
		(property "Value" ""
			(at 0 0 180)
			(layer "F.Fab")
			(effects
				(font
					(size 1.27 1.27)
				)
			)
		)
		(duplicate_pad_numbers_are_jumpers no)
		(fp_line
			(start 0.7874 0.4064)
			(end -0.7874 0.4064)
			(stroke
				(width 0.1524)
				(type default)
			)
			(layer "F.SilkS")
		)
		(fp_line
			(start 0.7874 -0.4064)
			(end 0.7874 0.4064)
			(stroke
				(width 0.1524)
				(type default)
			)
			(layer "F.SilkS")
		)
		(fp_line
			(start -0.7874 0.4064)
			(end -0.7874 -0.4064)
			(stroke
				(width 0.1524)
				(type default)
			)
			(layer "F.SilkS")
		)
		(fp_line
			(start -0.7874 -0.4064)
			(end 0.7874 -0.4064)
			(stroke
				(width 0.1524)
				(type default)
			)
			(layer "F.SilkS")
		)
		(fp_line
			(start 0.67945 0.3048)
			(end 0.120396 0.3048)
			(stroke
				(width 0.1)
				(type default)
			)
			(layer "F.Fab")
		)
		(fp_line
			(start 0.67945 -0.3048)
			(end 0.67945 0.3048)
			(stroke
				(width 0.1)
				(type default)
			)
			(layer "F.Fab")
		)
		(fp_line
			(start 0.12065 -0.2794)
			(end 0.12065 -0.3048)
			(stroke
				(width 0.1)
				(type default)
			)
			(layer "F.Fab")
		)
		(fp_line
			(start 0.12065 -0.3048)
			(end 0.67945 -0.3048)
			(stroke
				(width 0.1)
				(type default)
			)
			(layer "F.Fab")
		)
		(fp_line
			(start 0.120396 0.3048)
			(end 0.120396 0.2794)
			(stroke
				(width 0.1)
				(type default)
			)
			(layer "F.Fab")
		)
		(fp_line
			(start 0.120396 0.2794)
			(end -0.12065 0.2794)
			(stroke
				(width 0.1)
				(type default)
			)
			(layer "F.Fab")
		)
		(fp_line
			(start -0.12065 0.3048)
			(end -0.67945 0.3048)
			(stroke
				(width 0.1)
				(type default)
			)
			(layer "F.Fab")
		)
		(fp_line
			(start -0.12065 0.2794)
			(end -0.12065 0.3048)
			(stroke
				(width 0.1)
				(type default)
			)
			(layer "F.Fab")
		)
		(fp_line
			(start -0.12065 -0.2794)
			(end 0.12065 -0.2794)
			(stroke
				(width 0.1)
				(type default)
			)
			(layer "F.Fab")
		)
		(fp_line
			(start -0.12065 -0.305054)
			(end -0.12065 -0.2794)
			(stroke
				(width 0.1)
				(type default)
			)
			(layer "F.Fab")
		)
		(fp_line
			(start -0.67945 0.3048)
			(end -0.67945 -0.305054)
			(stroke
				(width 0.1)
				(type default)
			)
			(layer "F.Fab")
		)
		(fp_line
			(start -0.67945 -0.305054)
			(end -0.12065 -0.305054)
			(stroke
				(width 0.1)
				(type default)
			)
			(layer "F.Fab")
		)
		(pad "1" smd rect
			(at -0.40005 0)
			(size 0.4572 0.508)
			(layers "F.Cu" "F.Mask" "F.Paste")
			(net "P3V3_ADC")
		)
		(pad "2" smd rect
			(at 0.40005 0)
			(size 0.4572 0.508)
			(layers "F.Cu" "F.Mask" "F.Paste")
			(net "P3V3_ADC_TIC")
		)
	)
)
